# T6G (Grand Teton) — schematic netlist excerpt (pin names and nets, part order shuffled) for the footprints in the layout excerpt that follows; sources: Cadence DE-HDL packaged netlist, KiCad conversion of 04192023_DAF0TMB3IC0_F0TG_MB_C_brd_V02_OCP.brd

C2451  Q_CAP  22UF 4V 20% X6S  pkg C0402  page 74 : A = PVDDCR_SOC_P1 ; B = GND
PC571  Q_CAP  22UF 16V 20% X6S  pkg C0805  page 190 : A = SW_P3V3_AUX_FLT ; B = GND
R3504  Q_RES  100K 1% CHIP  pkg 0402LF  page 126 : A = P3V3_AUX ; B = GPU_FPGA_EROT_FATALERR_ISO_N

(kicad_pcb
	(version 20260206)
	(generator "pcbnew")
	(generator_version "10.0")
	(general
		(thickness 1.6)
		(legacy_teardrops no)
	)
	(paper "A4")
	(title_block
		(title "04192023_DAF0TMB3IC0_F0TG_MB_C_brd_V02_OCP.brd")
		(comment 1 "Grand Teton / footprints 8108-8110 of 8354")
	)
	(layers
		(0 "F.Cu" signal "TOP")
		(4 "In1.Cu" signal "GND")
		(6 "In2.Cu" signal "IN1")
		(8 "In3.Cu" signal "GND1")
		(10 "In4.Cu" signal "IN2")
		(12 "In5.Cu" signal "GND2")
		(14 "In6.Cu" signal "IN3")
		(16 "In7.Cu" signal "GND3")
		(18 "In8.Cu" signal "VCC")
		(20 "In9.Cu" signal "VCC1")
		(22 "In10.Cu" signal "GND4")
		(24 "In11.Cu" signal "IN4")
		(26 "In12.Cu" signal "GND5")
		(28 "In13.Cu" signal "IN5")
		(30 "In14.Cu" signal "GND6")
		(32 "In15.Cu" signal "IN6")
		(34 "In16.Cu" signal "GND7")
		(2 "B.Cu" signal "BOTTOM")
		(9 "F.Adhes" user "F.Adhesive")
		(11 "B.Adhes" user "B.Adhesive")
		(13 "F.Paste" user "Package Geometry/Pastemask Top")
		(15 "B.Paste" user "Package Geometry/Pastemask Bottom")
		(5 "F.SilkS" user "Ref Des/Silkscreen Top")
		(7 "B.SilkS" user "Ref Des/Silkscreen Bottom")
		(1 "F.Mask" user "Board Geometry/Soldermask Top")
		(3 "B.Mask" user "Board Geometry/Soldermask Bottom")
		(17 "Dwgs.User" user "User.Drawings")
		(19 "Cmts.User" user "User.Comments")
		(21 "Eco1.User" user "User.Eco1")
		(23 "Eco2.User" user "User.Eco2")
		(25 "Edge.Cuts" user "Board Geometry/Outline")
		(27 "Margin" user)
		(31 "F.CrtYd" user "Package Geometry/Place Bound Top")
		(29 "B.CrtYd" user "Package Geometry/Place Bound Bottom")
		(35 "F.Fab" user "Ref Des/Assembly Top")
		(33 "B.Fab" user "Ref Des/Assembly Bottom")
	)
	(footprint ""
		(layer "B.Cu")
		(at 117.388386 -251.781564)
		(property "Reference" "C2451"
			(at 0 0 0)
			(layer "B.SilkS")
			(hide yes)
			(effects
				(font
					(size 1.27 1.27)
				)
				(justify mirror)
			)
		)
		(property "Value" ""
			(at 0 0 0)
			(layer "B.Fab")
			(effects
				(font
					(size 1.27 1.27)
				)
				(justify mirror)
			)
		)
		(duplicate_pad_numbers_are_jumpers no)
		(fp_line
			(start -0.7874 -0.4064)
			(end -0.7874 0.4064)
			(stroke
				(width 0.1524)
				(type default)
			)
			(layer "B.SilkS")
		)
		(fp_line
			(start -0.7874 0.4064)
			(end 0.7874 0.4064)
			(stroke
				(width 0.1524)
				(type default)
			)
			(layer "B.SilkS")
		)
		(fp_line
			(start 0.7874 -0.4064)
			(end -0.7874 -0.4064)
			(stroke
				(width 0.1524)
				(type default)
			)
			(layer "B.SilkS")
		)
		(fp_line
			(start 0.7874 0.4064)
			(end 0.7874 -0.4064)
			(stroke
				(width 0.1524)
				(type default)
			)
			(layer "B.SilkS")
		)
		(fp_line
			(start -0.67945 -0.3048)
			(end -0.67945 0.3048)
			(stroke
				(width 0.1)
				(type default)
			)
			(layer "B.Fab")
		)
		(fp_line
			(start -0.67945 0.3048)
			(end -0.120396 0.3048)
			(stroke
				(width 0.1)
				(type default)
			)
			(layer "B.Fab")
		)
		(fp_line
			(start -0.12065 -0.3048)
			(end -0.67945 -0.3048)
			(stroke
				(width 0.1)
				(type default)
			)
			(layer "B.Fab")
		)
		(fp_line
			(start -0.12065 -0.2794)
			(end -0.12065 -0.3048)
			(stroke
				(width 0.1)
				(type default)
			)
			(layer "B.Fab")
		)
		(fp_line
			(start -0.120396 0.2794)
			(end 0.12065 0.2794)
			(stroke
				(width 0.1)
				(type default)
			)
			(layer "B.Fab")
		)
		(fp_line
			(start -0.120396 0.3048)
			(end -0.120396 0.2794)
			(stroke
				(width 0.1)
				(type default)
			)
			(layer "B.Fab")
		)
		(fp_line
			(start 0.12065 -0.305054)
			(end 0.12065 -0.2794)
			(stroke
				(width 0.1)
				(type default)
			)
			(layer "B.Fab")
		)
		(fp_line
			(start 0.12065 -0.2794)
			(end -0.12065 -0.2794)
			(stroke
				(width 0.1)
				(type default)
			)
			(layer "B.Fab")
		)
		(fp_line
			(start 0.12065 0.2794)
			(end 0.12065 0.3048)
			(stroke
				(width 0.1)
				(type default)
			)
			(layer "B.Fab")
		)
		(fp_line
			(start 0.12065 0.3048)
			(end 0.67945 0.3048)
			(stroke
				(width 0.1)
				(type default)
			)
			(layer "B.Fab")
		)
		(fp_line
			(start 0.67945 -0.305054)
			(end 0.12065 -0.305054)
			(stroke
				(width 0.1)
				(type default)
			)
			(layer "B.Fab")
		)
		(fp_line
			(start 0.67945 0.3048)
			(end 0.67945 -0.305054)
			(stroke
				(width 0.1)
				(type default)
			)
			(layer "B.Fab")
		)
		(pad "1" smd circle
			(at 0.40005 0 180)
			(size 0 0)
			(layers "B.Cu" "B.Mask" "B.Paste")
			(net "PVDDCR_SOC_P1")
		)
		(pad "2" smd circle
			(at -0.40005 0 180)
			(size 0 0)
			(layers "B.Cu" "B.Mask" "B.Paste")
			(net "GND")
		)
	)
	(footprint ""
		(layer "B.Cu")
		(at 449.789296 -52.846986 -90)
		(property "Reference" "PC571"
			(at 0 0 90)
			(layer "B.SilkS")
			(hide yes)
			(effects
				(font
					(size 1.27 1.27)
				)
				(justify mirror)
			)
		)
		(property "Value" ""
			(at 0 0 90)
			(layer "B.Fab")
			(effects
				(font
					(size 1.27 1.27)
				)
				(justify mirror)
			)
		)
		(duplicate_pad_numbers_are_jumpers no)
		(fp_line
			(start -1.524 0.762)
			(end 1.524 0.762)
			(stroke
				(width 0.1524)
				(type default)
			)
			(layer "B.SilkS")
		)
		(fp_line
			(start 1.524 0.762)
			(end 1.524 -0.762)
			(stroke
				(width 0.1524)
				(type default)
			)
			(layer "B.SilkS")
		)
		(fp_line
			(start -1.524 -0.762)
			(end -1.524 0.762)
			(stroke
				(width 0.1524)
				(type default)
			)
			(layer "B.SilkS")
		)
		(fp_line
			(start 1.524 -0.762)
			(end -1.524 -0.762)
			(stroke
				(width 0.1524)
				(type default)
			)
			(layer "B.SilkS")
		)
		(fp_line
			(start -1.1049 0.724916)
			(end -1.1049 -0.724916)
			(stroke
				(width 0.1)
				(type default)
			)
			(layer "B.Fab")
		)
		(fp_line
			(start 1.1049 0.724916)
			(end -1.1049 0.724916)
			(stroke
				(width 0.1)
				(type default)
			)
			(layer "B.Fab")
		)
		(fp_line
			(start -1.1049 -0.724916)
			(end 1.1049 -0.724916)
			(stroke
				(width 0.1)
				(type default)
			)
			(layer "B.Fab")
		)
		(fp_line
			(start 1.1049 -0.724916)
			(end 1.1049 0.724916)
			(stroke
				(width 0.1)
				(type default)
			)
			(layer "B.Fab")
		)
		(pad "1" smd rect
			(at 0.889 0 270)
			(size 1.016 1.27)
			(layers "B.Cu" "B.Mask" "B.Paste")
			(net "SW_P3V3_AUX_FLT")
		)
		(pad "2" smd rect
			(at -0.889 0 270)
			(size 1.016 1.27)
			(layers "B.Cu" "B.Mask" "B.Paste")
			(net "GND")
		)
	)
	(footprint ""
		(layer "B.Cu")
		(at 117.141244 -415.9123 -90)
		(property "Reference" "R3504"
			(at 0 0 90)
			(layer "B.SilkS")
			(hide yes)
			(effects
				(font
					(size 1.27 1.27)
				)
				(justify mirror)
			)
		)
		(property "Value" ""
			(at 0 0 90)
			(layer "B.Fab")
			(effects
				(font
					(size 1.27 1.27)
				)
				(justify mirror)
			)
		)
		(duplicate_pad_numbers_are_jumpers no)
		(fp_line
			(start -0.7874 0.4064)
			(end 0.7874 0.4064)
			(stroke
				(width 0.1524)
				(type default)
			)
			(layer "B.SilkS")
		)
		(fp_line
			(start 0.7874 0.4064)
			(end 0.7874 -0.4064)
			(stroke
				(width 0.1524)
				(type default)
			)
			(layer "B.SilkS")
		)
		(fp_line
			(start -0.7874 -0.4064)
			(end -0.7874 0.4064)
			(stroke
				(width 0.1524)
				(type default)
			)
			(layer "B.SilkS")
		)
		(fp_line
			(start 0.7874 -0.4064)
			(end -0.7874 -0.4064)
			(stroke
				(width 0.1524)
				(type default)
			)
			(layer "B.SilkS")
		)
		(fp_line
			(start -0.67945 0.3048)
			(end -0.120396 0.3048)
			(stroke
				(width 0.1)
				(type default)
			)
			(layer "B.Fab")
		)
		(fp_line
			(start -0.120396 0.3048)
			(end -0.120396 0.2794)
			(stroke
				(width 0.1)
				(type default)
			)
			(layer "B.Fab")
		)
		(fp_line
			(start 0.12065 0.3048)
			(end 0.67945 0.3048)
			(stroke
				(width 0.1)
				(type default)
			)
			(layer "B.Fab")
		)
		(fp_line
			(start 0.67945 0.3048)
			(end 0.67945 -0.305054)
			(stroke
				(width 0.1)
				(type default)
			)
			(layer "B.Fab")
		)
		(fp_line
			(start -0.120396 0.2794)
			(end 0.12065 0.2794)
			(stroke
				(width 0.1)
				(type default)
			)
			(layer "B.Fab")
		)
		(fp_line
			(start 0.12065 0.2794)
			(end 0.12065 0.3048)
			(stroke
				(width 0.1)
				(type default)
			)
			(layer "B.Fab")
		)
		(fp_line
			(start -0.12065 -0.2794)
			(end -0.12065 -0.3048)
			(stroke
				(width 0.1)
				(type default)
			)
			(layer "B.Fab")
		)
		(fp_line
			(start 0.12065 -0.2794)
			(end -0.12065 -0.2794)
			(stroke
				(width 0.1)
				(type default)
			)
			(layer "B.Fab")
		)
		(fp_line
			(start -0.67945 -0.3048)
			(end -0.67945 0.3048)
			(stroke
				(width 0.1)
				(type default)
			)
			(layer "B.Fab")
		)
		(fp_line
			(start -0.12065 -0.3048)
			(end -0.67945 -0.3048)
			(stroke
				(width 0.1)
				(type default)
			)
			(layer "B.Fab")
		)
		(fp_line
			(start 0.12065 -0.305054)
			(end 0.12065 -0.2794)
			(stroke
				(width 0.1)
				(type default)
			)
			(layer "B.Fab")
		)
		(fp_line
			(start 0.67945 -0.305054)
			(end 0.12065 -0.305054)
			(stroke
				(width 0.1)
				(type default)
			)
			(layer "B.Fab")
		)
		(pad "1" smd circle
			(at 0.40005 0 90)
			(size 0 0)
			(layers "B.Cu" "B.Mask" "B.Paste")
			(net "P3V3_AUX")
		)
		(pad "2" smd circle
			(at -0.40005 0 90)
			(size 0 0)
			(layers "B.Cu" "B.Mask" "B.Paste")
			(net "GPU_FPGA_EROT_FATALERR_ISO_N")
		)
	)
)
